FILE_TYPE = MACRO_DRAWING;
SET COLOR_WIRE YELLOW;
SET COLOR_PROP ORANGE;
SET COLOR_DOT WHITE;
SET COLOR_ARC YELLOW;
SET COLOR_BODY GREEN;
SET COLOR_NOTE PURPLE;
SET PROP_DISPLAY VALUE;
SET PAGE_NUMBER P140;
FORCEADD QUANTA_TITLE_BLOCK_C..1
(9675 -750);
FORCEPROP 1 LAST CUSTOM_TXT_CDS <NAME_2>
J 0
(6500 -700);
FORCEPROP 1 LAST CUSTOM_TXT_CDS <NAME_1>
J 0
(6500 -575);
FORCEPROP 1 LAST CUSTOM_TXT_CDS <Q_NUMBER>
J 0
(8272 -647);
DISPLAY 1.212766 (8272 -647);
FORCEPROP 1 LAST CUSTOM_TXT_CDS <Q_PROJ>
J 0
(7293 -648);
DISPLAY 1.212766 (7293 -648);
FORCEPROP 1 LAST CUSTOM_TXT_CDS <Q_REV>
J 0
(9491 -647);
DISPLAY 1.212766 (9491 -647);
FORCEPROP 1 LAST CUSTOM_TXT_CDS <CON_LAST_MODIFIED>
J 0
(7790 -735);
DISPLAY 0.978723 (7790 -735);
FORCEPROP 1 LAST CUSTOM_TXT_CDS <CON_PAGE_NUM> OF <CON_TOTAL_PAGES>
J 0
(9229 -732);
DISPLAY 0.978723 (9229 -732);
FORCEPROP 1 LAST Q_TITLE Blank
J 0
(375 -675);
DISPLAY 2.446809 (375 -675);
PAINT GREEN (375 -675);
FORCEPROP 2 LAST CDS_LIB pure_quanta
J 0
(9675 -750);
DISPLAY INVISIBLE (9675 -750);
FORCEPROP 1 LAST CDS_LMAN_SYM_OUTLINE -9475,6775,100,-125
J 0
(9675 -750);
DISPLAY 0.468085 (9675 -750);
PAINT GREEN (9675 -750);
DISPLAY INVISIBLE (9675 -750);
FORCEPROP 2 LAST PAGE_BORDER TRUE
J 0
(1785 4500);
DISPLAY 0.638298 (1785 4500);
PAINT PINK (1785 4500);
DISPLAY INVISIBLE (1785 4500);
FORCEPROP 2 LAST CDS_XR_PAGE_TITLE CR-163 : @T6G_MB_LIB.T6G(SCH_1):PAGE163
J 0
(1785 4500);
DISPLAY 0.638298 (1785 4500);
PAINT PINK (1785 4500);
DISPLAY INVISIBLE (1785 4500);
FORCEPROP 2 LAST CUSTOM_TXT_CDS <XR_PAGE_TITLE>
J 0
(1785 4500);
DISPLAY 0.638298 (1785 4500);
PAINT PINK (1785 4500);
DISPLAY INVISIBLE (1785 4500);
FORCEPROP 1 LAST COMMENT_BODY TRUE
J 0
(9687 -763);
DISPLAY 0.978723 (9687 -763);
PAINT GREEN (9687 -763);
DISPLAY INVISIBLE (9687 -763);
FORCEPROP 1 LAST Q_DEPT BU9
J 1
(5912 -701);
DISPLAY 1.957447 (5912 -701);
PAINT GREEN (5912 -701);
DISPLAY INVISIBLE (5912 -701);
FORCEPROP 0 LAST CDS_CON_LAST_MODIFIED Thu Aug 24 10:14:47 2023
J 0
(7790 -735);
DISPLAY INVISIBLE (7790 -735);
QUIT
